# T6G (Grand Teton) — schematic netlist excerpt (pin names and nets, part order shuffled) for the footprints in the layout excerpt that follows; sources: Cadence DE-HDL packaged netlist, KiCad conversion of 04192023_DAF0TMB3IC0_F0TG_MB_C_brd_V02_OCP.brd

PC419_3  Q_CAP  22UF 4V 20% X6S  pkg C0805  page 219 : A = PVDDCR_CPU1_P1 ; B = GND
C3919  Q_CAP  22UF 4V 20% X6S  pkg C0402  page 74 : A = PVDD11_S3_P1 ; B = GND
R2838  Q_RES  100K 1% CHIP  pkg 0402LF  page 127 : A = FM_SWB_PWRGD ; B = GND

(kicad_pcb
	(version 20260206)
	(generator "pcbnew")
	(generator_version "10.0")
	(general
		(thickness 1.6)
		(legacy_teardrops no)
	)
	(paper "A4")
	(title_block
		(title "04192023_DAF0TMB3IC0_F0TG_MB_C_brd_V02_OCP.brd")
		(comment 1 "Grand Teton / footprints 4956-4958 of 8354")
	)
	(layers
		(0 "F.Cu" signal "TOP")
		(4 "In1.Cu" signal "GND")
		(6 "In2.Cu" signal "IN1")
		(8 "In3.Cu" signal "GND1")
		(10 "In4.Cu" signal "IN2")
		(12 "In5.Cu" signal "GND2")
		(14 "In6.Cu" signal "IN3")
		(16 "In7.Cu" signal "GND3")
		(18 "In8.Cu" signal "VCC")
		(20 "In9.Cu" signal "VCC1")
		(22 "In10.Cu" signal "GND4")
		(24 "In11.Cu" signal "IN4")
		(26 "In12.Cu" signal "GND5")
		(28 "In13.Cu" signal "IN5")
		(30 "In14.Cu" signal "GND6")
		(32 "In15.Cu" signal "IN6")
		(34 "In16.Cu" signal "GND7")
		(2 "B.Cu" signal "BOTTOM")
		(9 "F.Adhes" user "F.Adhesive")
		(11 "B.Adhes" user "B.Adhesive")
		(13 "F.Paste" user "Package Geometry/Pastemask Top")
		(15 "B.Paste" user "Package Geometry/Pastemask Bottom")
		(5 "F.SilkS" user "Ref Des/Silkscreen Top")
		(7 "B.SilkS" user "Ref Des/Silkscreen Bottom")
		(1 "F.Mask" user "Board Geometry/Soldermask Top")
		(3 "B.Mask" user "Board Geometry/Soldermask Bottom")
		(17 "Dwgs.User" user "User.Drawings")
		(19 "Cmts.User" user "User.Comments")
		(21 "Eco1.User" user "User.Eco1")
		(23 "Eco2.User" user "User.Eco2")
		(25 "Edge.Cuts" user "Board Geometry/Outline")
		(27 "Margin" user)
		(31 "F.CrtYd" user "Package Geometry/Place Bound Top")
		(29 "B.CrtYd" user "Package Geometry/Place Bound Bottom")
		(35 "F.Fab" user "Ref Des/Assembly Top")
		(33 "B.Fab" user "Ref Des/Assembly Bottom")
	)
	(footprint ""
		(layer "B.Cu")
		(at 123.357386 -266.005564)
		(property "Reference" "C3919"
			(at 0 0 0)
			(layer "B.SilkS")
			(hide yes)
			(effects
				(font
					(size 1.27 1.27)
				)
				(justify mirror)
			)
		)
		(property "Value" ""
			(at 0 0 0)
			(layer "B.Fab")
			(effects
				(font
					(size 1.27 1.27)
				)
				(justify mirror)
			)
		)
		(duplicate_pad_numbers_are_jumpers no)
		(fp_line
			(start -0.7874 -0.4064)
			(end -0.7874 0.4064)
			(stroke
				(width 0.1524)
				(type default)
			)
			(layer "B.SilkS")
		)
		(fp_line
			(start -0.7874 0.4064)
			(end 0.7874 0.4064)
			(stroke
				(width 0.1524)
				(type default)
			)
			(layer "B.SilkS")
		)
		(fp_line
			(start 0.7874 -0.4064)
			(end -0.7874 -0.4064)
			(stroke
				(width 0.1524)
				(type default)
			)
			(layer "B.SilkS")
		)
		(fp_line
			(start 0.7874 0.4064)
			(end 0.7874 -0.4064)
			(stroke
				(width 0.1524)
				(type default)
			)
			(layer "B.SilkS")
		)
		(fp_line
			(start -0.67945 -0.3048)
			(end -0.67945 0.3048)
			(stroke
				(width 0.1)
				(type default)
			)
			(layer "B.Fab")
		)
		(fp_line
			(start -0.67945 0.3048)
			(end -0.120396 0.3048)
			(stroke
				(width 0.1)
				(type default)
			)
			(layer "B.Fab")
		)
		(fp_line
			(start -0.12065 -0.3048)
			(end -0.67945 -0.3048)
			(stroke
				(width 0.1)
				(type default)
			)
			(layer "B.Fab")
		)
		(fp_line
			(start -0.12065 -0.2794)
			(end -0.12065 -0.3048)
			(stroke
				(width 0.1)
				(type default)
			)
			(layer "B.Fab")
		)
		(fp_line
			(start -0.120396 0.2794)
			(end 0.12065 0.2794)
			(stroke
				(width 0.1)
				(type default)
			)
			(layer "B.Fab")
		)
		(fp_line
			(start -0.120396 0.3048)
			(end -0.120396 0.2794)
			(stroke
				(width 0.1)
				(type default)
			)
			(layer "B.Fab")
		)
		(fp_line
			(start 0.12065 -0.305054)
			(end 0.12065 -0.2794)
			(stroke
				(width 0.1)
				(type default)
			)
			(layer "B.Fab")
		)
		(fp_line
			(start 0.12065 -0.2794)
			(end -0.12065 -0.2794)
			(stroke
				(width 0.1)
				(type default)
			)
			(layer "B.Fab")
		)
		(fp_line
			(start 0.12065 0.2794)
			(end 0.12065 0.3048)
			(stroke
				(width 0.1)
				(type default)
			)
			(layer "B.Fab")
		)
		(fp_line
			(start 0.12065 0.3048)
			(end 0.67945 0.3048)
			(stroke
				(width 0.1)
				(type default)
			)
			(layer "B.Fab")
		)
		(fp_line
			(start 0.67945 -0.305054)
			(end 0.12065 -0.305054)
			(stroke
				(width 0.1)
				(type default)
			)
			(layer "B.Fab")
		)
		(fp_line
			(start 0.67945 0.3048)
			(end 0.67945 -0.305054)
			(stroke
				(width 0.1)
				(type default)
			)
			(layer "B.Fab")
		)
		(pad "1" smd circle
			(at 0.40005 0 180)
			(size 0 0)
			(layers "B.Cu" "B.Mask" "B.Paste")
			(net "PVDD11_S3_P1")
		)
		(pad "2" smd circle
			(at -0.40005 0 180)
			(size 0 0)
			(layers "B.Cu" "B.Mask" "B.Paste")
			(net "GND")
		)
	)
	(footprint ""
		(layer "B.Cu")
		(at 359.539794 -419.027864 180)
		(property "Reference" "R2838"
			(at 0 0 0)
			(layer "B.SilkS")
			(hide yes)
			(effects
				(font
					(size 1.27 1.27)
				)
				(justify mirror)
			)
		)
		(property "Value" ""
			(at 0 0 0)
			(layer "B.Fab")
			(effects
				(font
					(size 1.27 1.27)
				)
				(justify mirror)
			)
		)
		(duplicate_pad_numbers_are_jumpers no)
		(fp_line
			(start 0.7874 0.4064)
			(end 0.7874 -0.4064)
			(stroke
				(width 0.1524)
				(type default)
			)
			(layer "B.SilkS")
		)
		(fp_line
			(start 0.7874 -0.4064)
			(end -0.7874 -0.4064)
			(stroke
				(width 0.1524)
				(type default)
			)
			(layer "B.SilkS")
		)
		(fp_line
			(start -0.7874 0.4064)
			(end 0.7874 0.4064)
			(stroke
				(width 0.1524)
				(type default)
			)
			(layer "B.SilkS")
		)
		(fp_line
			(start -0.7874 -0.4064)
			(end -0.7874 0.4064)
			(stroke
				(width 0.1524)
				(type default)
			)
			(layer "B.SilkS")
		)
		(fp_line
			(start 0.67945 0.3048)
			(end 0.67945 -0.305054)
			(stroke
				(width 0.1)
				(type default)
			)
			(layer "B.Fab")
		)
		(fp_line
			(start 0.67945 -0.305054)
			(end 0.12065 -0.305054)
			(stroke
				(width 0.1)
				(type default)
			)
			(layer "B.Fab")
		)
		(fp_line
			(start 0.12065 0.3048)
			(end 0.67945 0.3048)
			(stroke
				(width 0.1)
				(type default)
			)
			(layer "B.Fab")
		)
		(fp_line
			(start 0.12065 0.2794)
			(end 0.12065 0.3048)
			(stroke
				(width 0.1)
				(type default)
			)
			(layer "B.Fab")
		)
		(fp_line
			(start 0.12065 -0.2794)
			(end -0.12065 -0.2794)
			(stroke
				(width 0.1)
				(type default)
			)
			(layer "B.Fab")
		)
		(fp_line
			(start 0.12065 -0.305054)
			(end 0.12065 -0.2794)
			(stroke
				(width 0.1)
				(type default)
			)
			(layer "B.Fab")
		)
		(fp_line
			(start -0.120396 0.3048)
			(end -0.120396 0.2794)
			(stroke
				(width 0.1)
				(type default)
			)
			(layer "B.Fab")
		)
		(fp_line
			(start -0.120396 0.2794)
			(end 0.12065 0.2794)
			(stroke
				(width 0.1)
				(type default)
			)
			(layer "B.Fab")
		)
		(fp_line
			(start -0.12065 -0.2794)
			(end -0.12065 -0.3048)
			(stroke
				(width 0.1)
				(type default)
			)
			(layer "B.Fab")
		)
		(fp_line
			(start -0.12065 -0.3048)
			(end -0.67945 -0.3048)
			(stroke
				(width 0.1)
				(type default)
			)
			(layer "B.Fab")
		)
		(fp_line
			(start -0.67945 0.3048)
			(end -0.120396 0.3048)
			(stroke
				(width 0.1)
				(type default)
			)
			(layer "B.Fab")
		)
		(fp_line
			(start -0.67945 -0.3048)
			(end -0.67945 0.3048)
			(stroke
				(width 0.1)
				(type default)
			)
			(layer "B.Fab")
		)
		(pad "1" smd circle
			(at 0.40005 0)
			(size 0 0)
			(layers "B.Cu" "B.Mask" "B.Paste")
			(net "FM_SWB_PWRGD")
		)
		(pad "2" smd circle
			(at -0.40005 0)
			(size 0 0)
			(layers "B.Cu" "B.Mask" "B.Paste")
			(net "GND")
		)
	)
	(footprint ""
		(layer "B.Cu")
		(at 58.418476 -338.086954 -90)
		(property "Reference" "PC419_3"
			(at 0 0 90)
			(layer "B.SilkS")
			(hide yes)
			(effects
				(font
					(size 1.27 1.27)
				)
				(justify mirror)
			)
		)
		(property "Value" ""
			(at 0 0 90)
			(layer "B.Fab")
			(effects
				(font
					(size 1.27 1.27)
				)
				(justify mirror)
			)
		)
		(duplicate_pad_numbers_are_jumpers no)
		(fp_line
			(start -1.524 0.762)
			(end 1.524 0.762)
			(stroke
				(width 0.1524)
				(type default)
			)
			(layer "B.SilkS")
		)
		(fp_line
			(start 1.524 0.762)
			(end 1.524 -0.762)
			(stroke
				(width 0.1524)
				(type default)
			)
			(layer "B.SilkS")
		)
		(fp_line
			(start -1.524 -0.762)
			(end -1.524 0.762)
			(stroke
				(width 0.1524)
				(type default)
			)
			(layer "B.SilkS")
		)
		(fp_line
			(start 1.524 -0.762)
			(end -1.524 -0.762)
			(stroke
				(width 0.1524)
				(type default)
			)
			(layer "B.SilkS")
		)
		(fp_line
			(start -1.1049 0.724916)
			(end -1.1049 -0.724916)
			(stroke
				(width 0.1)
				(type default)
			)
			(layer "B.Fab")
		)
		(fp_line
			(start 1.1049 0.724916)
			(end -1.1049 0.724916)
			(stroke
				(width 0.1)
				(type default)
			)
			(layer "B.Fab")
		)
		(fp_line
			(start -1.1049 -0.724916)
			(end 1.1049 -0.724916)
			(stroke
				(width 0.1)
				(type default)
			)
			(layer "B.Fab")
		)
		(fp_line
			(start 1.1049 -0.724916)
			(end 1.1049 0.724916)
			(stroke
				(width 0.1)
				(type default)
			)
			(layer "B.Fab")
		)
		(pad "1" smd rect
			(at 0.889 0 270)
			(size 1.016 1.27)
			(layers "B.Cu" "B.Mask" "B.Paste")
			(net "PVDDCR_CPU1_P1")
		)
		(pad "2" smd rect
			(at -0.889 0 270)
			(size 1.016 1.27)
			(layers "B.Cu" "B.Mask" "B.Paste")
			(net "GND")
		)
	)
)
